FILE_TYPE = CONNECTIVITY;
{Allegro Design Entry HDL 16.6-p007 (v16-6-112F) 10/10/2012}
"PAGE_NUMBER" = 122;
0"NC";
1"P1V8_PCH_STBY\g";
2"P1V05_PCH_STBY\g";
3"P3V3_STBY\g";
4"P1V05_PCH_STBY_WM26_PLL\g";
5"P1V05_PCH_STBY_WM20_PLL\g";
6"P1V05_PCH_STBY_KR_PLL\g";
7"P1V05_PCH_STBY_ISCLK_PLL\g";
8"P1V05_PCH_STBY_VCCA_XTAL\g";
9"P3V3_RTC_STBY\g";
10"P1V05_PCH_STBY\g";
11"P1V05_PCH_STBY_VCCA_PLL0\g";
12"P1V05_PCH_STBY_VCCA_PLL1\g";
13"TP_PCH_RSVD28";
14"TP_PCH_RSVD29";
15"TP_PCH_RSVD30";
16"TP_PCH_RSVD31";
17"TP_PCH_RSVD58";
18"TP_PCH_RSVD59";
19"A_PVCCRTC_EXT_CAP";
%"P1V8_PCH_STBY"
"1","(-1450,4925)","2","mstr_symbols","I21";
;
HDL_POWER"P1V8_PCH_STBY"
BODY_TYPE"PLUMBING"
CDS_LIB"mstr_symbols"
VOLTAGE"1.8V";
"G\NAC"1;
%"P1V05_PCH_STBY"
"1","(-5650,5225)","0","mstr_symbols","I24";
;
HDL_POWER"P1V05_PCH_STBY"
BODY_TYPE"PLUMBING"
CDS_LIB"mstr_symbols"
VOLTAGE"1.05V";
"G\NAC"2;
%"LBG_CORE_QAT_EXT_D"
"9","(-3900,3075)","0","mstr_u_proc","I63";
;
CDS_SEC"9"
ROOM"SB"
SEC_TYPE"BGA1"
SEC"9"
CDS_LOCATION"U7C1"
BOM_COST"SB"
CDS_LIB"mstr_u_proc"
PACK_TYPE"BGA1"
MATERIAL"IC"
PART_NUMBER"H91415-002"
LOCATION"U7C1";
"VCCPSPI"
$PN"AR24"3;
"VCCP_3P3<5>"
$PN"AN24"3;
"VCCPDSW_3P3"
$PN"AH24"3;
"VCCPUSBDSW_3P3"
$PN"BA48"3;
"VCCMPHY_1P05<12>"
$PN"AK43"2;
"VCCMPHY_1P05<10>"
$PN"AM43"2;
"VCCMPHY_1P05<9>"
$PN"AM45"2;
"VCCP_UPPLLUNF_1P05"
$PN"AM48"2;
"VCCP_UPPLL_1P05<0>"
$PN"AN50"5;
"VCCP_HSIOPLLUNF_1P05"
$PN"AT48"2;
"VCCP_HSIOPLL_1P05<2>"
$PN"AU48"4;
"VCCP_HSIOPLL_1P05<3>"
$PN"AP48"4;
"VCCA_PLL0_1P05"
$PN"AG48"11;
"VCCA_PLL1_1P05"
$PN"AE45"12;
"VCCPRIM_1P05<17>"
$PN"AK27"2;
"RSVD<59>"
$PN"AT27"18;
"RSVD<58>"
$PN"AP27"17;
"RSVD<31>"
$PN"P29"16;
"RSVD<30>"
$PN"R31"15;
"RSVD<29>"
$PN"P33"14;
"RSVD<28>"
$PN"R35"13;
"VCCA_CLKFILT_1P05<4>"
$PN"AE46"7;
"VCCA_CLKFILT_1P05<3>"
$PN"AJ48"7;
"VCCA_CLKFILT_1P05<2>"
$PN"AJ46"7;
"VCCA_CLKFILT_1P05<1>"
$PN"AG45"7;
"VCCA_CLKFILT_1P05<0>"
$PN"W50"7;
"VCCA_CLKUNF_1P05<1>"
$PN"U50"2;
"VCCA_CLKUNF_1P05<0>"
$PN"AH50"2;
"VCCA_CLKXTAL_1P05"
$PN"AD50"8;
"VCCMPHY_1P05<11>"
$PN"AK45"2;
"VCCMPHY_1P05<8>"
$PN"AP43"2;
"VCCMPHY_1P05<7>"
$PN"AP45"2;
"VCCMPHY_1P05<6>"
$PN"AT43"2;
"VCCMPHY_1P05<5>"
$PN"AT45"2;
"VCCMPHY_1P05<4>"
$PN"AU43"2;
"VCCMPHY_1P05<3>"
$PN"AU45"2;
"VCCMPHY_1P05<2>"
$PN"AJ43"2;
"VCCMPHY_1P05<1>"
$PN"AW43"2;
"VCCMPHY_1P05<0>"
$PN"AW45"2;
"VCCP10GBEPLL_1P05<3>"
$PN"BA39"6;
"VCCP10GBEPLL_1P05<2>"
$PN"BA41"6;
"VCCP10GBEPLL_1P05<1>"
$PN"BB40"6;
"VCCP10GBEPLL_1P05<0>"
$PN"BD38"6;
"VCCP10GBE_HV_1P8<1>"
$PN"BA27"1;
"VCCP10GBE_HV_1P8<0>"
$PN"BA29"1;
"VCCP10GBE_LV_1P05<6>"
$PN"BA30"2;
"VCCP10GBE_LV_1P05<5>"
$PN"BA32"2;
"VCCP10GBE_LV_1P05<4>"
$PN"BA34"2;
"VCCP10GBE_LV_1P05<3>"
$PN"BA36"2;
"VCCP10GBE_LV_1P05<2>"
$PN"BA37"2;
"VCCP10GBE_LV_1P05<1>"
$PN"BB33"2;
"VCCP10GBE_LV_1P05<0>"
$PN"BB37"2;
"VCCPGPPA"
$PN"AW24"3;
"VCCPGPPB"
$PN"BE26"3;
"VCCPGPPC"
$PN"BE40"3;
"VCCPGPPD"
$PN"BA43"3;
"VCCPGPPE"
$PN"BE44"3;
"VCCPGPPF"
$PN"AU27"3;
"VCCPGPPG"
$PN"BA26"3;
"VCCPGPPH"
$PN"BA24"3;
"VCCPGPPJ"
$PN"BB26"3;
"VCCPGPPK"
$PN"AU24"3;
"VCCPGPP_1P8<6>"
$PN"AK24"1;
"VCCPGPP_1P8<5>"
$PN"AW27"1;
"VCCPGPP_1P8<4>"
$PN"AP29"1;
"VCCPGPP_1P8<3>"
$PN"AM29"1;
"VCCPGPP_1P8<2>"
$PN"AT29"1;
"VCCPGPP_1P8<1>"
$PN"AW29"1;
"VCCPGPP_1P8<0>"
$PN"AU29"1;
"VCCPHDA_1P8"
$PN"AG27"1;
"VCCPRIM_1P05<19>"
$PN"Y26"10;
"VCCPRIM_1P05<18>"
$PN"AA24"10;
"VCCPRIM_1P05<16>"
$PN"R42"2;
"VCCPRIM_1P05<15>"
$PN"R46"2;
"VCCPRIM_1P05<14>"
$PN"T44"2;
"VCCPRIM_1P05<13>"
$PN"U46"2;
"VCCPRIM_1P05<12>"
$PN"V44"2;
"VCCPRIM_1P05<11>"
$PN"Y45"2;
"VCCPRIM_1P05<10>"
$PN"Y46"2;
"VCCPRIM_1P05<9>"
$PN"AA45"2;
"VCCPRIM_1P05<8>"
$PN"AA46"2;
"VCCPRIM_1P05<7>"
$PN"AC26"2;
"VCCPRIM_1P05<6>"
$PN"AJ29"2;
"VCCPRIM_1P05<5>"
$PN"AM27"2;
"VCCPRIM_1P05<4>"
$PN"AT39"2;
"VCCPRIM_1P05<3>"
$PN"AU37"2;
"VCCPRIM_1P05<2>"
$PN"AU39"2;
"VCCPRIM_1P05<1>"
$PN"BE48"2;
"VCCPRIM_1P05<0>"
$PN"BF46"2;
"VCCPRTC"
$PN"AJ27"9;
"VCCPRTCPRIM_3P3"
$PN"AG29"3;
"VCCPSPI_1P8"
$PN"AK29"1;
"VCCP_1P8<1>"
$PN"AE26"1;
"VCCP_1P8<0>"
$PN"BD46"1;
"VCCP_3P3<2>"
$PN"AD24"3;
"VCCP_3P3<1>"
$PN"BA45"3;
"VCCP_3P3<0>"
$PN"BA46"3;
"VCCP_HSIOPLL_1P05<0>"
$PN"AW48"4;
"VCCP_UPPLL_1P05<2>"
$PN"AK50"5;
"VCCRTCEXT"
$PN"AG22"19;
%"P3V3_STBY"
"1","(-1150,3025)","0","mstr_symbols","I65";
;
HDL_POWER"P3V3_STBY"
BODY_TYPE"PLUMBING"
CDS_LIB"mstr_symbols"
SIZE"1B"
VOLTAGE"3.3V";
"G\NAC"3;
%"P1V05_PCH_STBY_WM26_PLL"
"1","(-6725,3050)","0","mstr_symbols","I70";
;
HDL_POWER"P1V05_PCH_STBY_WM26_PLL"
ROOM"SB_DECOUPLING"
BODY_TYPE"PLUMBING"
BOM_COST"SB"
CDS_LIB"mstr_symbols"
VOLTAGE"1.05V";
"G\NAC"4;
%"P1V05_PCH_STBY_WM20_PLL"
"1","(-6975,3225)","0","mstr_symbols","I71";
;
HDL_POWER"P1V05_PCH_STBY_WM20_PLL"
ROOM"SB_DECOUPLING"
BODY_TYPE"PLUMBING"
CDS_LIB"mstr_symbols"
BOM_COST"SB"
VOLTAGE"1.05V";
"G\NAC"5;
%"P1V05_PCH_STBY_KR_PLL"
"1","(-7275,3350)","0","mstr_symbols","I72";
;
HDL_POWER"P1V05_PCH_STBY_KR_PLL"
ROOM"SB_DECOUPLING"
BODY_TYPE"PLUMBING"
CDS_LIB"mstr_symbols"
BOM_COST"SB"
VOLTAGE"1.05V";
"G\NAC"6;
%"P1V05_PCH_STBY_ISCLK_PLL"
"1","(-7575,3475)","0","mstr_symbols","I73";
;
HDL_POWER"P1V05_PCH_STBY_ISCLK_PLL"
ROOM"SB_DECOUPLING"
BODY_TYPE"PLUMBING"
CDS_LIB"mstr_symbols"
BOM_COST"SB"
VOLTAGE"1.05V";
"G\NAC"7;
%"P1V05_PCH_STBY_VCCA_XTAL"
"1","(-7900,3650)","0","mstr_symbols","I74";
;
HDL_POWER"P1V05_PCH_STBY_VCCA_XTAL"
ROOM"SB_DECOUPLING"
BODY_TYPE"PLUMBING"
CDS_LIB"mstr_symbols"
BOM_COST"SB"
VOLTAGE"1.05V";
"G\NAC"8;
%"P3V3_RTC_STBY"
"1","(-675,3000)","0","mstr_symbols","I75";
;
HDL_POWER"P3V3_RTC_STBY"
ROOM"SB_DECOUPLING"
BODY_TYPE"PLUMBING"
CDS_LIB"mstr_symbols"
BOM_COST"SB"
VOLTAGE"3.3V";
"G\NAC"9;
%"P1V05_PCH_STBY"
"1","(-1925,3475)","0","mstr_symbols","I76";
;
HDL_POWER"P1V05_PCH_STBY"
BODY_TYPE"PLUMBING"
CDS_LIB"mstr_symbols"
VOLTAGE"1.05V";
"G\NAC"10;
%"P1V05_PCH_STBY_VCCA_PLL0"
"1","(-6525,2925)","0","mstr_symbols","I77";
;
HDL_POWER"P1V05_PCH_STBY_VCCA_PLL0"
ROOM"SB_DECOUPLING"
BODY_TYPE"PLUMBING"
BOM_COST"SB"
CDS_LIB"mstr_symbols"
VOLTAGE"1.05V";
"G\NAC"11;
%"P1V05_PCH_STBY_VCCA_PLL1"
"1","(-6325,2800)","0","mstr_symbols","I78";
;
HDL_POWER"P1V05_PCH_STBY_VCCA_PLL1"
ROOM"SB_DECOUPLING"
BODY_TYPE"PLUMBING"
CDS_LIB"mstr_symbols"
BOM_COST"SB"
VOLTAGE"1.05V";
"G\NAC"12;
END.
